# S9S_MB_2U (Grand Teton) — schematic netlist excerpt (pin names and nets, part order shuffled) for the footprints in the layout excerpt that follows; sources: Cadence DE-HDL packaged netlist, KiCad conversion of 03242023_DA0F0TMBIJ0_F0T_Motherboard_J_brd_V01_OCP.brd

R1368  Q_RES  1K 1% CHIP  pkg 0402LF  page 239 : A = PD_JTAG_DBP_B2 ; B = GND
C819  Q_CAP_DIFFBUS  DIFF BUS_0.22UF 6.3V 20% X6S  pkg C0201  page 175 : \1\ = P5E_CPU1_PE1_TX_C_DP<9> ; \2\ = P5E_CPU1_PE1_TX_DP<9>
C1818  Q_CAP  0.1UF 25V 10% X7R  pkg 0402  page 164 : A = P3V3_AUX ; B = GND

(kicad_pcb
	(version 20260206)
	(generator "pcbnew")
	(generator_version "10.0")
	(general
		(thickness 1.6)
		(legacy_teardrops no)
	)
	(paper "A4")
	(title_block
		(title "03242023_DA0F0TMBIJ0_F0T_Motherboard_J_brd_V01_OCP.brd")
		(comment 1 "Grand Teton / footprints 2704-2706 of 6105")
	)
	(layers
		(0 "F.Cu" signal "TOP")
		(4 "In1.Cu" signal "GND")
		(6 "In2.Cu" signal "IN1")
		(8 "In3.Cu" signal "GND1")
		(10 "In4.Cu" signal "IN2")
		(12 "In5.Cu" signal "GND2")
		(14 "In6.Cu" signal "IN3")
		(16 "In7.Cu" signal "GND3")
		(18 "In8.Cu" signal "VCC")
		(20 "In9.Cu" signal "VCC1")
		(22 "In10.Cu" signal "GND4")
		(24 "In11.Cu" signal "IN4")
		(26 "In12.Cu" signal "GND5")
		(28 "In13.Cu" signal "IN5")
		(30 "In14.Cu" signal "GND6")
		(32 "In15.Cu" signal "IN6")
		(34 "In16.Cu" signal "GND7")
		(2 "B.Cu" signal "BOTTOM")
		(9 "F.Adhes" user "F.Adhesive")
		(11 "B.Adhes" user "B.Adhesive")
		(13 "F.Paste" user "Package Geometry/Pastemask Top")
		(15 "B.Paste" user "Package Geometry/Pastemask Bottom")
		(5 "F.SilkS" user "Ref Des/Silkscreen Top")
		(7 "B.SilkS" user "Ref Des/Silkscreen Bottom")
		(1 "F.Mask" user "Board Geometry/Soldermask Top")
		(3 "B.Mask" user "Board Geometry/Soldermask Bottom")
		(17 "Dwgs.User" user "User.Drawings")
		(19 "Cmts.User" user "User.Comments")
		(21 "Eco1.User" user "User.Eco1")
		(23 "Eco2.User" user "User.Eco2")
		(25 "Edge.Cuts" user "Board Geometry/Outline")
		(27 "Margin" user)
		(31 "F.CrtYd" user "Package Geometry/Place Bound Top")
		(29 "B.CrtYd" user "Package Geometry/Place Bound Bottom")
		(35 "F.Fab" user "Ref Des/Assembly Top")
		(33 "B.Fab" user "Ref Des/Assembly Bottom")
	)
	(footprint ""
		(layer "F.Cu")
		(at 376.271536 -105.483152 90)
		(property "Reference" "R1368"
			(at 0 0 90)
			(layer "F.SilkS")
			(hide yes)
			(effects
				(font
					(size 1.27 1.27)
				)
			)
		)
		(property "Value" ""
			(at 0 0 90)
			(layer "F.Fab")
			(effects
				(font
					(size 1.27 1.27)
				)
			)
		)
		(duplicate_pad_numbers_are_jumpers no)
		(fp_line
			(start 0.7874 -0.4064)
			(end 0.7874 0.4064)
			(stroke
				(width 0.1524)
				(type default)
			)
			(layer "F.SilkS")
		)
		(fp_line
			(start -0.7874 -0.4064)
			(end 0.7874 -0.4064)
			(stroke
				(width 0.1524)
				(type default)
			)
			(layer "F.SilkS")
		)
		(fp_line
			(start 0.7874 0.4064)
			(end -0.7874 0.4064)
			(stroke
				(width 0.1524)
				(type default)
			)
			(layer "F.SilkS")
		)
		(fp_line
			(start -0.7874 0.4064)
			(end -0.7874 -0.4064)
			(stroke
				(width 0.1524)
				(type default)
			)
			(layer "F.SilkS")
		)
		(fp_line
			(start -0.12065 -0.305054)
			(end -0.12065 -0.2794)
			(stroke
				(width 0.1)
				(type default)
			)
			(layer "F.Fab")
		)
		(fp_line
			(start -0.67945 -0.305054)
			(end -0.12065 -0.305054)
			(stroke
				(width 0.1)
				(type default)
			)
			(layer "F.Fab")
		)
		(fp_line
			(start 0.67945 -0.3048)
			(end 0.67945 0.3048)
			(stroke
				(width 0.1)
				(type default)
			)
			(layer "F.Fab")
		)
		(fp_line
			(start 0.12065 -0.3048)
			(end 0.67945 -0.3048)
			(stroke
				(width 0.1)
				(type default)
			)
			(layer "F.Fab")
		)
		(fp_line
			(start 0.12065 -0.2794)
			(end 0.12065 -0.3048)
			(stroke
				(width 0.1)
				(type default)
			)
			(layer "F.Fab")
		)
		(fp_line
			(start -0.12065 -0.2794)
			(end 0.12065 -0.2794)
			(stroke
				(width 0.1)
				(type default)
			)
			(layer "F.Fab")
		)
		(fp_line
			(start 0.120396 0.2794)
			(end -0.12065 0.2794)
			(stroke
				(width 0.1)
				(type default)
			)
			(layer "F.Fab")
		)
		(fp_line
			(start -0.12065 0.2794)
			(end -0.12065 0.3048)
			(stroke
				(width 0.1)
				(type default)
			)
			(layer "F.Fab")
		)
		(fp_line
			(start 0.67945 0.3048)
			(end 0.120396 0.3048)
			(stroke
				(width 0.1)
				(type default)
			)
			(layer "F.Fab")
		)
		(fp_line
			(start 0.120396 0.3048)
			(end 0.120396 0.2794)
			(stroke
				(width 0.1)
				(type default)
			)
			(layer "F.Fab")
		)
		(fp_line
			(start -0.12065 0.3048)
			(end -0.67945 0.3048)
			(stroke
				(width 0.1)
				(type default)
			)
			(layer "F.Fab")
		)
		(fp_line
			(start -0.67945 0.3048)
			(end -0.67945 -0.305054)
			(stroke
				(width 0.1)
				(type default)
			)
			(layer "F.Fab")
		)
		(pad "1" smd circle
			(at -0.40005 0 90)
			(size 0 0)
			(layers "F.Cu" "F.Mask" "F.Paste")
			(net "PD_JTAG_DBP_B2")
		)
		(pad "2" smd circle
			(at 0.40005 0 90)
			(size 0 0)
			(layers "F.Cu" "F.Mask" "F.Paste")
			(net "GND")
		)
	)
	(footprint ""
		(layer "F.Cu")
		(at 132.15874 -115.585748 180)
		(property "Reference" "C1818"
			(at 0 0 180)
			(layer "F.SilkS")
			(hide yes)
			(effects
				(font
					(size 1.27 1.27)
				)
			)
		)
		(property "Value" ""
			(at 0 0 180)
			(layer "F.Fab")
			(effects
				(font
					(size 1.27 1.27)
				)
			)
		)
		(duplicate_pad_numbers_are_jumpers no)
		(fp_line
			(start 0.7874 0.4064)
			(end -0.7874 0.4064)
			(stroke
				(width 0.1524)
				(type default)
			)
			(layer "F.SilkS")
		)
		(fp_line
			(start 0.7874 -0.4064)
			(end 0.7874 0.4064)
			(stroke
				(width 0.1524)
				(type default)
			)
			(layer "F.SilkS")
		)
		(fp_line
			(start -0.7874 0.4064)
			(end -0.7874 -0.4064)
			(stroke
				(width 0.1524)
				(type default)
			)
			(layer "F.SilkS")
		)
		(fp_line
			(start -0.7874 -0.4064)
			(end 0.7874 -0.4064)
			(stroke
				(width 0.1524)
				(type default)
			)
			(layer "F.SilkS")
		)
		(fp_line
			(start 0.67945 0.3048)
			(end 0.120396 0.3048)
			(stroke
				(width 0.1)
				(type default)
			)
			(layer "F.Fab")
		)
		(fp_line
			(start 0.67945 -0.3048)
			(end 0.67945 0.3048)
			(stroke
				(width 0.1)
				(type default)
			)
			(layer "F.Fab")
		)
		(fp_line
			(start 0.12065 -0.2794)
			(end 0.12065 -0.3048)
			(stroke
				(width 0.1)
				(type default)
			)
			(layer "F.Fab")
		)
		(fp_line
			(start 0.12065 -0.3048)
			(end 0.67945 -0.3048)
			(stroke
				(width 0.1)
				(type default)
			)
			(layer "F.Fab")
		)
		(fp_line
			(start 0.120396 0.3048)
			(end 0.120396 0.2794)
			(stroke
				(width 0.1)
				(type default)
			)
			(layer "F.Fab")
		)
		(fp_line
			(start 0.120396 0.2794)
			(end -0.12065 0.2794)
			(stroke
				(width 0.1)
				(type default)
			)
			(layer "F.Fab")
		)
		(fp_line
			(start -0.12065 0.3048)
			(end -0.67945 0.3048)
			(stroke
				(width 0.1)
				(type default)
			)
			(layer "F.Fab")
		)
		(fp_line
			(start -0.12065 0.2794)
			(end -0.12065 0.3048)
			(stroke
				(width 0.1)
				(type default)
			)
			(layer "F.Fab")
		)
		(fp_line
			(start -0.12065 -0.2794)
			(end 0.12065 -0.2794)
			(stroke
				(width 0.1)
				(type default)
			)
			(layer "F.Fab")
		)
		(fp_line
			(start -0.12065 -0.305054)
			(end -0.12065 -0.2794)
			(stroke
				(width 0.1)
				(type default)
			)
			(layer "F.Fab")
		)
		(fp_line
			(start -0.67945 0.3048)
			(end -0.67945 -0.305054)
			(stroke
				(width 0.1)
				(type default)
			)
			(layer "F.Fab")
		)
		(fp_line
			(start -0.67945 -0.305054)
			(end -0.12065 -0.305054)
			(stroke
				(width 0.1)
				(type default)
			)
			(layer "F.Fab")
		)
		(pad "1" smd circle
			(at -0.40005 0 180)
			(size 0 0)
			(layers "F.Cu" "F.Mask" "F.Paste")
			(net "P3V3_AUX")
		)
		(pad "2" smd circle
			(at 0.40005 0 180)
			(size 0 0)
			(layers "F.Cu" "F.Mask" "F.Paste")
			(net "GND")
		)
	)
	(footprint ""
		(layer "F.Cu")
		(at 32.272478 -16.099536 90)
		(property "Reference" "C819"
			(at 0 0 90)
			(layer "F.SilkS")
			(hide yes)
			(effects
				(font
					(size 1.27 1.27)
				)
			)
		)
		(property "Value" ""
			(at 0 0 90)
			(layer "F.Fab")
			(effects
				(font
					(size 1.27 1.27)
				)
			)
		)
		(duplicate_pad_numbers_are_jumpers no)
		(fp_line
			(start 0.299974 -0.150114)
			(end 0.299974 0.150114)
			(stroke
				(width 0.1)
				(type default)
			)
			(layer "F.Fab")
		)
		(fp_line
			(start -0.299974 -0.150114)
			(end 0.299974 -0.150114)
			(stroke
				(width 0.1)
				(type default)
			)
			(layer "F.Fab")
		)
		(fp_line
			(start 0.299974 0.150114)
			(end -0.299974 0.150114)
			(stroke
				(width 0.1)
				(type default)
			)
			(layer "F.Fab")
		)
		(fp_line
			(start -0.299974 0.150114)
			(end -0.299974 -0.150114)
			(stroke
				(width 0.1)
				(type default)
			)
			(layer "F.Fab")
		)
		(pad "1" smd rect
			(at -0.2667 0 90)
			(size 0.3048 0.381)
			(layers "F.Cu" "F.Mask" "F.Paste")
			(net "P5E_CPU1_PE1_TX_C_DP<9>")
		)
		(pad "2" smd rect
			(at 0.2667 0 90)
			(size 0.3048 0.381)
			(layers "F.Cu" "F.Mask" "F.Paste")
			(net "P5E_CPU1_PE1_TX_DP<9>")
		)
	)
)
